(kicad_pcb
	(version 20260206)
	(generator "pcbnew")
	(generator_version "10.0")
	(general
		(thickness 1.6)
		(legacy_teardrops no)
	)
	(paper "A4")
	(title_block
		(title "timecard-production-celestica-r4006 — R4006-B0001-02_R01.brd")
		(comment 1 "Time Appliance Project (Time Card) / footprints 852-856 of 1113")
	)
	(layers
		(0 "F.Cu" signal "TOP")
		(4 "In1.Cu" signal "L02_GND1")
		(6 "In2.Cu" signal "L03_SIG1")
		(8 "In3.Cu" signal "L04_GND2")
		(10 "In4.Cu" signal "L05_VCC1")
		(12 "In5.Cu" signal "L06_VCC2")
		(14 "In6.Cu" signal "L07_GND3")
		(16 "In7.Cu" signal "L08_SIG2")
		(18 "In8.Cu" signal "L09_GND4")
		(2 "B.Cu" signal "BOTTOM")
		(9 "F.Adhes" user "F.Adhesive")
		(11 "B.Adhes" user "B.Adhesive")
		(13 "F.Paste" user "Package Geometry/Pastemask Top")
		(15 "B.Paste" user "Package Geometry/Pastemask Bottom")
		(5 "F.SilkS" user "Ref Des/Silkscreen Top")
		(7 "B.SilkS" user "Ref Des/Silkscreen Bottom")
		(1 "F.Mask" user "Board Geometry/Soldermask Top")
		(3 "B.Mask" user "Board Geometry/Soldermask Bottom")
		(17 "Dwgs.User" user "User.Drawings")
		(19 "Cmts.User" user "User.Comments")
		(21 "Eco1.User" user "User.Eco1")
		(23 "Eco2.User" user "User.Eco2")
		(25 "Edge.Cuts" user "Board Geometry/Outline")
		(27 "Margin" user)
		(31 "F.CrtYd" user "Package Geometry/Place Bound Top")
		(29 "B.CrtYd" user "Package Geometry/Place Bound Bottom")
		(35 "F.Fab" user "Ref Des/Assembly Top")
		(33 "B.Fab" user "Ref Des/Assembly Bottom")
	)
	(footprint ""
		(layer "B.Cu")
		(at 22.4028 -90.7796 -90)
		(property "Reference" "R468"
			(at -2.5654 4.40817 270)
			(unlocked yes)
			(layer "B.SilkS")
			(effects
				(font
					(size 0.7874 0.5842)
					(thickness 0.1524)
				)
				(justify mirror)
			)
		)
		(property "Value" "VAL*"
			(at -0.02032 2.13233 270)
			(unlocked yes)
			(layer "B.Fab")
			(hide yes)
			(effects
				(font
					(size 0.7874 0.5842)
					(thickness 0.1524)
				)
				(justify mirror)
			)
		)
		(property "Tolerance" "TOL*"
			(at -0.044704 3.05435 270)
			(unlocked yes)
			(layer "Cmts.User")
			(hide yes)
			(effects
				(font
					(size 0.7874 0.5842)
					(thickness 0.1524)
				)
				(justify mirror)
			)
		)
		(property "User Part Number" "PARTNUM*"
			(at -0.02032 4.024884 270)
			(unlocked yes)
			(layer "Cmts.User")
			(hide yes)
			(effects
				(font
					(size 0.7874 0.5842)
					(thickness 0.1524)
				)
				(justify mirror)
			)
		)
		(property "Device Type" "RESISTOR-G155-133R0-01,33OHM,1%"
			(at -0.008382 1.210564 270)
			(unlocked yes)
			(layer "B.Fab")
			(hide yes)
			(effects
				(font
					(size 0.7874 0.5842)
					(thickness 0.1524)
				)
				(justify mirror)
			)
		)
		(duplicate_pad_numbers_are_jumpers no)
		(fp_line
			(start -1.143 0.5588)
			(end -1.143 -0.5588)
			(stroke
				(width 0.1)
				(type default)
			)
			(layer "B.SilkS")
		)
		(fp_line
			(start 1.143 0.5588)
			(end -1.143 0.5588)
			(stroke
				(width 0.1)
				(type default)
			)
			(layer "B.SilkS")
		)
		(fp_line
			(start -1.143 -0.5588)
			(end 1.143 -0.5588)
			(stroke
				(width 0.1)
				(type default)
			)
			(layer "B.SilkS")
		)
		(fp_line
			(start 1.143 -0.5588)
			(end 1.143 0.5588)
			(stroke
				(width 0.1)
				(type default)
			)
			(layer "B.SilkS")
		)
		(fp_poly
			(pts
				(xy 1.143 0.5588) (xy -1.143 0.5588) (xy -1.143 -0.5588) (xy 1.143 -0.5588)
			)
			(stroke
				(width 0)
				(type default)
			)
			(fill no)
			(layer "B.CrtYd")
		)
		(fp_line
			(start -0.508 0.3048)
			(end -0.508 -0.3048)
			(stroke
				(width 0.1)
				(type default)
			)
			(layer "B.Fab")
		)
		(fp_line
			(start 0.508 0.3048)
			(end -0.508 0.3048)
			(stroke
				(width 0.1)
				(type default)
			)
			(layer "B.Fab")
		)
		(fp_line
			(start -0.508 -0.3048)
			(end 0.508 -0.3048)
			(stroke
				(width 0.1)
				(type default)
			)
			(layer "B.Fab")
		)
		(fp_line
			(start 0.508 -0.3048)
			(end 0.508 0.3048)
			(stroke
				(width 0.1)
				(type default)
			)
			(layer "B.Fab")
		)
		(pad "1" smd rect
			(at 0.5334 0 90)
			(size 0.7112 0.6096)
			(layers "B.Cu" "B.Mask" "B.Paste")
			(net "R_FT4232_TDI")
		)
		(pad "2" smd rect
			(at -0.5334 0 90)
			(size 0.7112 0.6096)
			(layers "B.Cu" "B.Mask" "B.Paste")
			(net "FT4232_TDI_MOSI")
		)
		(zone
			(layer "B.Cu")
			(hatch none 0.5)
			(connect_pads
				(clearance 0)
			)
			(min_thickness 0.25)
			(keepout
				(tracks allowed)
				(vias not_allowed)
				(pads allowed)
				(copperpour not_allowed)
				(footprints allowed)
			)
			(placement
				(enabled no)
				(sheetname "")
			)
			(fill
				(thermal_gap 0.5)
				(thermal_bridge_width 0.5)
				(island_removal_mode 0)
			)
			(polygon
				(pts
					(xy 22.098 -90.7034) (xy 22.7076 -90.7034) (xy 22.7076 -90.8558) (xy 22.098 -90.8558)
				)
			)
		)
		(zone
			(layer "B.Cu")
			(hatch none 0.5)
			(connect_pads
				(clearance 0)
			)
			(min_thickness 0.25)
			(keepout
				(tracks not_allowed)
				(vias allowed)
				(pads allowed)
				(copperpour not_allowed)
				(footprints allowed)
			)
			(placement
				(enabled no)
				(sheetname "")
			)
			(fill
				(thermal_gap 0.5)
				(thermal_bridge_width 0.5)
				(island_removal_mode 0)
			)
			(polygon
				(pts
					(xy 22.098 -90.7034) (xy 22.7076 -90.7034) (xy 22.7076 -90.8558) (xy 22.098 -90.8558)
				)
			)
		)
	)
	(footprint ""
		(layer "B.Cu")
		(at 141.097 -107.696 90)
		(property "Reference" "R258"
			(at -0.762 1.03505 270)
			(unlocked yes)
			(layer "B.SilkS")
			(effects
				(font
					(size 0.635 0.4064)
					(thickness 0.1524)
				)
				(justify mirror)
			)
		)
		(property "Value" "VAL*"
			(at -0.02032 2.13233 90)
			(unlocked yes)
			(layer "B.Fab")
			(hide yes)
			(effects
				(font
					(size 0.7874 0.5842)
					(thickness 0.1524)
				)
				(justify mirror)
			)
		)
		(property "Device Type" "RESISTOR-G155-13300-01,330OHM,A"
			(at -0.008382 1.210564 90)
			(unlocked yes)
			(layer "B.Fab")
			(hide yes)
			(effects
				(font
					(size 0.7874 0.5842)
					(thickness 0.1524)
				)
				(justify mirror)
			)
		)
		(property "User Part Number" "PARTNUM*"
			(at -0.02032 4.024884 90)
			(unlocked yes)
			(layer "Cmts.User")
			(hide yes)
			(effects
				(font
					(size 0.7874 0.5842)
					(thickness 0.1524)
				)
				(justify mirror)
			)
		)
		(property "Tolerance" "TOL*"
			(at -0.044704 3.05435 90)
			(unlocked yes)
			(layer "Cmts.User")
			(hide yes)
			(effects
				(font
					(size 0.7874 0.5842)
					(thickness 0.1524)
				)
				(justify mirror)
			)
		)
		(duplicate_pad_numbers_are_jumpers no)
		(fp_line
			(start 1.143 -0.5588)
			(end 1.143 0.5588)
			(stroke
				(width 0.1)
				(type default)
			)
			(layer "B.SilkS")
		)
		(fp_line
			(start -1.143 -0.5588)
			(end 1.143 -0.5588)
			(stroke
				(width 0.1)
				(type default)
			)
			(layer "B.SilkS")
		)
		(fp_line
			(start 1.143 0.5588)
			(end -1.143 0.5588)
			(stroke
				(width 0.1)
				(type default)
			)
			(layer "B.SilkS")
		)
		(fp_line
			(start -1.143 0.5588)
			(end -1.143 -0.5588)
			(stroke
				(width 0.1)
				(type default)
			)
			(layer "B.SilkS")
		)
		(fp_rect
			(start -1.143 -0.5588)
			(end 1.143 0.5588)
			(stroke
				(width 0)
				(type default)
			)
			(fill no)
			(layer "B.CrtYd")
		)
		(fp_line
			(start 0.508 -0.3048)
			(end 0.508 0.3048)
			(stroke
				(width 0.1)
				(type default)
			)
			(layer "B.Fab")
		)
		(fp_line
			(start -0.508 -0.3048)
			(end 0.508 -0.3048)
			(stroke
				(width 0.1)
				(type default)
			)
			(layer "B.Fab")
		)
		(fp_line
			(start 0.508 0.3048)
			(end -0.508 0.3048)
			(stroke
				(width 0.1)
				(type default)
			)
			(layer "B.Fab")
		)
		(fp_line
			(start -0.508 0.3048)
			(end -0.508 -0.3048)
			(stroke
				(width 0.1)
				(type default)
			)
			(layer "B.Fab")
		)
		(pad "1" smd rect
			(at 0.5334 0 270)
			(size 0.7112 0.6096)
			(layers "B.Cu" "B.Mask" "B.Paste")
			(net "UNNAMED_14_OPTICAL_I11_A")
		)
		(pad "2" smd rect
			(at -0.5334 0 270)
			(size 0.7112 0.6096)
			(layers "B.Cu" "B.Mask" "B.Paste")
			(net "XP3R3V_FPGA")
		)
		(zone
			(layer "B.Cu")
			(hatch none 0.5)
			(connect_pads
				(clearance 0)
			)
			(min_thickness 0.25)
			(keepout
				(tracks allowed)
				(vias not_allowed)
				(pads allowed)
				(copperpour not_allowed)
				(footprints allowed)
			)
			(placement
				(enabled no)
				(sheetname "")
			)
			(fill
				(thermal_gap 0.5)
				(thermal_bridge_width 0.5)
				(island_removal_mode 0)
			)
			(polygon
				(pts
					(xy 140.7922 -107.6198) (xy 141.4018 -107.6198) (xy 141.4018 -107.7722) (xy 140.7922 -107.7722)
				)
			)
		)
	)
	(footprint ""
		(layer "B.Cu")
		(at 82.931 -103.378)
		(property "Reference" "C56"
			(at -2.413 0.03937 0)
			(unlocked yes)
			(layer "B.SilkS")
			(effects
				(font
					(size 0.7874 0.5842)
					(thickness 0.1524)
				)
				(justify mirror)
			)
		)
		(property "Value" "VAL*"
			(at -0.0762 2.067306 0)
			(unlocked yes)
			(layer "B.Fab")
			(hide yes)
			(effects
				(font
					(size 0.7874 0.5842)
					(thickness 0.1524)
				)
				(justify mirror)
			)
		)
		(property "Tolerance" "TOL*"
			(at -0.0762 3.032506 0)
			(unlocked yes)
			(layer "Cmts.User")
			(hide yes)
			(effects
				(font
					(size 0.7874 0.5842)
					(thickness 0.1524)
				)
				(justify mirror)
			)
		)
		(property "User Part Number" "PARTNUM*"
			(at -0.1016 4.023106 0)
			(unlocked yes)
			(layer "Cmts.User")
			(hide yes)
			(effects
				(font
					(size 0.7874 0.5842)
					(thickness 0.1524)
				)
				(justify mirror)
			)
		)
		(property "Device Type" "CAPACITOR-G105-0B104-EK,0.1UF,A"
			(at -0.0508 1.127506 0)
			(unlocked yes)
			(layer "B.Fab")
			(hide yes)
			(effects
				(font
					(size 0.7874 0.5842)
					(thickness 0.1524)
				)
				(justify mirror)
			)
		)
		(duplicate_pad_numbers_are_jumpers no)
		(fp_line
			(start -1.143 -0.5588)
			(end 1.143 -0.5588)
			(stroke
				(width 0.1)
				(type default)
			)
			(layer "B.SilkS")
		)
		(fp_line
			(start -1.143 0.5588)
			(end -1.143 -0.5588)
			(stroke
				(width 0.1)
				(type default)
			)
			(layer "B.SilkS")
		)
		(fp_line
			(start 1.143 -0.5588)
			(end 1.143 0.5588)
			(stroke
				(width 0.1)
				(type default)
			)
			(layer "B.SilkS")
		)
		(fp_line
			(start 1.143 0.5588)
			(end -1.143 0.5588)
			(stroke
				(width 0.1)
				(type default)
			)
			(layer "B.SilkS")
		)
		(fp_rect
			(start 1.143 0.5588)
			(end -1.143 -0.5588)
			(stroke
				(width 0)
				(type default)
			)
			(fill no)
			(layer "B.CrtYd")
		)
		(fp_line
			(start -0.508 -0.3048)
			(end 0.508 -0.3048)
			(stroke
				(width 0.1)
				(type default)
			)
			(layer "B.Fab")
		)
		(fp_line
			(start -0.508 0.3048)
			(end -0.508 -0.3048)
			(stroke
				(width 0.1)
				(type default)
			)
			(layer "B.Fab")
		)
		(fp_line
			(start 0.508 -0.3048)
			(end 0.508 0.3048)
			(stroke
				(width 0.1)
				(type default)
			)
			(layer "B.Fab")
		)
		(fp_line
			(start 0.508 0.3048)
			(end -0.508 0.3048)
			(stroke
				(width 0.1)
				(type default)
			)
			(layer "B.Fab")
		)
		(pad "1" smd rect
			(at 0.5334 0 180)
			(size 0.7112 0.6096)
			(layers "B.Cu" "B.Mask" "B.Paste")
			(net "UNNAMED_517_CAPACITOR_I27_1")
		)
		(pad "2" smd rect
			(at -0.5334 0 180)
			(size 0.7112 0.6096)
			(layers "B.Cu" "B.Mask" "B.Paste")
			(net "XP3R3V_SW")
		)
		(zone
			(layer "B.Cu")
			(hatch none 0.5)
			(connect_pads
				(clearance 0)
			)
			(min_thickness 0.25)
			(keepout
				(tracks allowed)
				(vias not_allowed)
				(pads allowed)
				(copperpour not_allowed)
				(footprints allowed)
			)
			(placement
				(enabled no)
				(sheetname "")
			)
			(fill
				(thermal_gap 0.5)
				(thermal_bridge_width 0.5)
				(island_removal_mode 0)
			)
			(polygon
				(pts
					(xy 83.0072 -103.0732) (xy 83.0072 -103.6828) (xy 82.8548 -103.6828) (xy 82.8548 -103.0732)
				)
			)
		)
	)
	(footprint ""
		(layer "B.Cu")
		(at 32.512 -79.121 90)
		(property "Reference" "R131"
			(at 0.254 1.10363 270)
			(unlocked yes)
			(layer "B.SilkS")
			(effects
				(font
					(size 0.7874 0.5842)
					(thickness 0.1524)
				)
				(justify mirror)
			)
		)
		(property "Value" "VAL*"
			(at -0.02032 2.13233 90)
			(unlocked yes)
			(layer "B.Fab")
			(hide yes)
			(effects
				(font
					(size 0.7874 0.5842)
					(thickness 0.1524)
				)
				(justify mirror)
			)
		)
		(property "Tolerance" "TOL*"
			(at -0.044704 3.05435 90)
			(unlocked yes)
			(layer "Cmts.User")
			(hide yes)
			(effects
				(font
					(size 0.7874 0.5842)
					(thickness 0.1524)
				)
				(justify mirror)
			)
		)
		(property "User Part Number" "PARTNUM*"
			(at -0.02032 4.024884 90)
			(unlocked yes)
			(layer "Cmts.User")
			(hide yes)
			(effects
				(font
					(size 0.7874 0.5842)
					(thickness 0.1524)
				)
				(justify mirror)
			)
		)
		(property "Device Type" "RESISTOR-G155-11000-01,100OHM,A"
			(at -0.008382 1.210564 90)
			(unlocked yes)
			(layer "B.Fab")
			(hide yes)
			(effects
				(font
					(size 0.7874 0.5842)
					(thickness 0.1524)
				)
				(justify mirror)
			)
		)
		(duplicate_pad_numbers_are_jumpers no)
		(fp_line
			(start 1.143 -0.5588)
			(end 1.143 0.5588)
			(stroke
				(width 0.1)
				(type default)
			)
			(layer "B.SilkS")
		)
		(fp_line
			(start -1.143 -0.5588)
			(end 1.143 -0.5588)
			(stroke
				(width 0.1)
				(type default)
			)
			(layer "B.SilkS")
		)
		(fp_line
			(start 1.143 0.5588)
			(end -1.143 0.5588)
			(stroke
				(width 0.1)
				(type default)
			)
			(layer "B.SilkS")
		)
		(fp_line
			(start -1.143 0.5588)
			(end -1.143 -0.5588)
			(stroke
				(width 0.1)
				(type default)
			)
			(layer "B.SilkS")
		)
		(fp_rect
			(start 1.143 -0.5588)
			(end -1.143 0.5588)
			(stroke
				(width 0)
				(type default)
			)
			(fill no)
			(layer "B.CrtYd")
		)
		(fp_line
			(start 0.508 -0.3048)
			(end 0.508 0.3048)
			(stroke
				(width 0.1)
				(type default)
			)
			(layer "B.Fab")
		)
		(fp_line
			(start -0.508 -0.3048)
			(end 0.508 -0.3048)
			(stroke
				(width 0.1)
				(type default)
			)
			(layer "B.Fab")
		)
		(fp_line
			(start 0.508 0.3048)
			(end -0.508 0.3048)
			(stroke
				(width 0.1)
				(type default)
			)
			(layer "B.Fab")
		)
		(fp_line
			(start -0.508 0.3048)
			(end -0.508 -0.3048)
			(stroke
				(width 0.1)
				(type default)
			)
			(layer "B.Fab")
		)
		(pad "1" smd rect
			(at 0.5334 0 270)
			(size 0.7112 0.6096)
			(layers "B.Cu" "B.Mask" "B.Paste")
			(net "R_FT4232_CHD_TX")
		)
		(pad "2" smd rect
			(at -0.5334 0 270)
			(size 0.7112 0.6096)
			(layers "B.Cu" "B.Mask" "B.Paste")
			(net "FT4232_CHD_TX")
		)
		(zone
			(layer "B.Cu")
			(hatch none 0.5)
			(connect_pads
				(clearance 0)
			)
			(min_thickness 0.25)
			(keepout
				(tracks allowed)
				(vias not_allowed)
				(pads allowed)
				(copperpour not_allowed)
				(footprints allowed)
			)
			(placement
				(enabled no)
				(sheetname "")
			)
			(fill
				(thermal_gap 0.5)
				(thermal_bridge_width 0.5)
				(island_removal_mode 0)
			)
			(polygon
				(pts
					(xy 32.2072 -79.1972) (xy 32.2072 -79.0448) (xy 32.8168 -79.0448) (xy 32.8168 -79.1972)
				)
			)
		)
	)
	(footprint ""
		(layer "B.Cu")
		(at 135.2042 -106.172254 90)
		(property "Reference" "R208"
			(at -7.747254 0.90043 270)
			(unlocked yes)
			(layer "B.SilkS")
			(effects
				(font
					(size 0.7874 0.5842)
					(thickness 0.1524)
				)
				(justify mirror)
			)
		)
		(property "Value" "VAL*"
			(at -0.02032 2.13233 90)
			(unlocked yes)
			(layer "B.Fab")
			(hide yes)
			(effects
				(font
					(size 0.7874 0.5842)
					(thickness 0.1524)
				)
				(justify mirror)
			)
		)
		(property "Device Type" "RESISTOR-G155-13300-01,330OHM,A"
			(at -0.008382 1.210564 90)
			(unlocked yes)
			(layer "B.Fab")
			(hide yes)
			(effects
				(font
					(size 0.7874 0.5842)
					(thickness 0.1524)
				)
				(justify mirror)
			)
		)
		(property "User Part Number" "PARTNUM*"
			(at -0.02032 4.024884 90)
			(unlocked yes)
			(layer "Cmts.User")
			(hide yes)
			(effects
				(font
					(size 0.7874 0.5842)
					(thickness 0.1524)
				)
				(justify mirror)
			)
		)
		(property "Tolerance" "TOL*"
			(at -0.044704 3.05435 90)
			(unlocked yes)
			(layer "Cmts.User")
			(hide yes)
			(effects
				(font
					(size 0.7874 0.5842)
					(thickness 0.1524)
				)
				(justify mirror)
			)
		)
		(duplicate_pad_numbers_are_jumpers no)
		(fp_line
			(start 1.143 -0.5588)
			(end 1.143 0.5588)
			(stroke
				(width 0.1)
				(type default)
			)
			(layer "B.SilkS")
		)
		(fp_line
			(start -1.143 -0.5588)
			(end 1.143 -0.5588)
			(stroke
				(width 0.1)
				(type default)
			)
			(layer "B.SilkS")
		)
		(fp_line
			(start 1.143 0.5588)
			(end -1.143 0.5588)
			(stroke
				(width 0.1)
				(type default)
			)
			(layer "B.SilkS")
		)
		(fp_line
			(start -1.143 0.5588)
			(end -1.143 -0.5588)
			(stroke
				(width 0.1)
				(type default)
			)
			(layer "B.SilkS")
		)
		(fp_rect
			(start -1.143 -0.5588)
			(end 1.143 0.5588)
			(stroke
				(width 0)
				(type default)
			)
			(fill no)
			(layer "B.CrtYd")
		)
		(fp_line
			(start 0.508 -0.3048)
			(end 0.508 0.3048)
			(stroke
				(width 0.1)
				(type default)
			)
			(layer "B.Fab")
		)
		(fp_line
			(start -0.508 -0.3048)
			(end 0.508 -0.3048)
			(stroke
				(width 0.1)
				(type default)
			)
			(layer "B.Fab")
		)
		(fp_line
			(start 0.508 0.3048)
			(end -0.508 0.3048)
			(stroke
				(width 0.1)
				(type default)
			)
			(layer "B.Fab")
		)
		(fp_line
			(start -0.508 0.3048)
			(end -0.508 -0.3048)
			(stroke
				(width 0.1)
				(type default)
			)
			(layer "B.Fab")
		)
		(pad "1" smd rect
			(at 0.5334 0 270)
			(size 0.7112 0.6096)
			(layers "B.Cu" "B.Mask" "B.Paste")
			(net "UNNAMED_14_OPTICAL_I292_A")
		)
		(pad "2" smd rect
			(at -0.5334 0 270)
			(size 0.7112 0.6096)
			(layers "B.Cu" "B.Mask" "B.Paste")
			(net "FPGA_DONE")
		)
		(zone
			(layer "B.Cu")
			(hatch none 0.5)
			(connect_pads
				(clearance 0)
			)
			(min_thickness 0.25)
			(keepout
				(tracks allowed)
				(vias not_allowed)
				(pads allowed)
				(copperpour not_allowed)
				(footprints allowed)
			)
			(placement
				(enabled no)
				(sheetname "")
			)
			(fill
				(thermal_gap 0.5)
				(thermal_bridge_width 0.5)
				(island_removal_mode 0)
			)
			(polygon
				(pts
					(xy 134.8994 -106.096054) (xy 135.509 -106.096054) (xy 135.509 -106.248454) (xy 134.8994 -106.248454)
				)
			)
		)
	)
)
